# T6G (Grand Teton) — schematic netlist excerpt (pin names and nets, part order shuffled) for the footprints in the layout excerpt that follows; sources: Cadence DE-HDL packaged netlist, KiCad conversion of 04192023_DAF0TMB3IC0_F0TG_MB_C_brd_V02_OCP.brd

C79  Q_CAP  0.1UF 25V 10% X7R  pkg 0402  page 182 : A = P3V3_9ZXL045_P0_VDD ; B = GND
R3095  Q_RES  130 1% CHIP  pkg 0402LF  page 256 : A = LED_PWRGD_PVDDIO_P1_R ; B = P3V3_AUX

(kicad_pcb
	(version 20260206)
	(generator "pcbnew")
	(generator_version "10.0")
	(general
		(thickness 1.6)
		(legacy_teardrops no)
	)
	(paper "A4")
	(title_block
		(title "04192023_DAF0TMB3IC0_F0TG_MB_C_brd_V02_OCP.brd")
		(comment 1 "Grand Teton / footprints 6433-6434 of 8354")
	)
	(layers
		(0 "F.Cu" signal "TOP")
		(4 "In1.Cu" signal "GND")
		(6 "In2.Cu" signal "IN1")
		(8 "In3.Cu" signal "GND1")
		(10 "In4.Cu" signal "IN2")
		(12 "In5.Cu" signal "GND2")
		(14 "In6.Cu" signal "IN3")
		(16 "In7.Cu" signal "GND3")
		(18 "In8.Cu" signal "VCC")
		(20 "In9.Cu" signal "VCC1")
		(22 "In10.Cu" signal "GND4")
		(24 "In11.Cu" signal "IN4")
		(26 "In12.Cu" signal "GND5")
		(28 "In13.Cu" signal "IN5")
		(30 "In14.Cu" signal "GND6")
		(32 "In15.Cu" signal "IN6")
		(34 "In16.Cu" signal "GND7")
		(2 "B.Cu" signal "BOTTOM")
		(9 "F.Adhes" user "F.Adhesive")
		(11 "B.Adhes" user "B.Adhesive")
		(13 "F.Paste" user "Package Geometry/Pastemask Top")
		(15 "B.Paste" user "Package Geometry/Pastemask Bottom")
		(5 "F.SilkS" user "Ref Des/Silkscreen Top")
		(7 "B.SilkS" user "Ref Des/Silkscreen Bottom")
		(1 "F.Mask" user "Board Geometry/Soldermask Top")
		(3 "B.Mask" user "Board Geometry/Soldermask Bottom")
		(17 "Dwgs.User" user "User.Drawings")
		(19 "Cmts.User" user "User.Comments")
		(21 "Eco1.User" user "User.Eco1")
		(23 "Eco2.User" user "User.Eco2")
		(25 "Edge.Cuts" user "Board Geometry/Outline")
		(27 "Margin" user)
		(31 "F.CrtYd" user "Package Geometry/Place Bound Top")
		(29 "B.CrtYd" user "Package Geometry/Place Bound Bottom")
		(35 "F.Fab" user "Ref Des/Assembly Top")
		(33 "B.Fab" user "Ref Des/Assembly Bottom")
	)
	(footprint ""
		(layer "B.Cu")
		(at 342.923876 -66.708782 90)
		(property "Reference" "R3095"
			(at 0 0 90)
			(layer "B.SilkS")
			(hide yes)
			(effects
				(font
					(size 1.27 1.27)
				)
				(justify mirror)
			)
		)
		(property "Value" ""
			(at 0 0 90)
			(layer "B.Fab")
			(effects
				(font
					(size 1.27 1.27)
				)
				(justify mirror)
			)
		)
		(duplicate_pad_numbers_are_jumpers no)
		(fp_line
			(start 0.7874 -0.4064)
			(end -0.7874 -0.4064)
			(stroke
				(width 0.1524)
				(type default)
			)
			(layer "B.SilkS")
		)
		(fp_line
			(start -0.7874 -0.4064)
			(end -0.7874 0.4064)
			(stroke
				(width 0.1524)
				(type default)
			)
			(layer "B.SilkS")
		)
		(fp_line
			(start 0.7874 0.4064)
			(end 0.7874 -0.4064)
			(stroke
				(width 0.1524)
				(type default)
			)
			(layer "B.SilkS")
		)
		(fp_line
			(start -0.7874 0.4064)
			(end 0.7874 0.4064)
			(stroke
				(width 0.1524)
				(type default)
			)
			(layer "B.SilkS")
		)
		(fp_line
			(start 0.67945 -0.305054)
			(end 0.12065 -0.305054)
			(stroke
				(width 0.1)
				(type default)
			)
			(layer "B.Fab")
		)
		(fp_line
			(start 0.12065 -0.305054)
			(end 0.12065 -0.2794)
			(stroke
				(width 0.1)
				(type default)
			)
			(layer "B.Fab")
		)
		(fp_line
			(start -0.12065 -0.3048)
			(end -0.67945 -0.3048)
			(stroke
				(width 0.1)
				(type default)
			)
			(layer "B.Fab")
		)
		(fp_line
			(start -0.67945 -0.3048)
			(end -0.67945 0.3048)
			(stroke
				(width 0.1)
				(type default)
			)
			(layer "B.Fab")
		)
		(fp_line
			(start 0.12065 -0.2794)
			(end -0.12065 -0.2794)
			(stroke
				(width 0.1)
				(type default)
			)
			(layer "B.Fab")
		)
		(fp_line
			(start -0.12065 -0.2794)
			(end -0.12065 -0.3048)
			(stroke
				(width 0.1)
				(type default)
			)
			(layer "B.Fab")
		)
		(fp_line
			(start 0.12065 0.2794)
			(end 0.12065 0.3048)
			(stroke
				(width 0.1)
				(type default)
			)
			(layer "B.Fab")
		)
		(fp_line
			(start -0.120396 0.2794)
			(end 0.12065 0.2794)
			(stroke
				(width 0.1)
				(type default)
			)
			(layer "B.Fab")
		)
		(fp_line
			(start 0.67945 0.3048)
			(end 0.67945 -0.305054)
			(stroke
				(width 0.1)
				(type default)
			)
			(layer "B.Fab")
		)
		(fp_line
			(start 0.12065 0.3048)
			(end 0.67945 0.3048)
			(stroke
				(width 0.1)
				(type default)
			)
			(layer "B.Fab")
		)
		(fp_line
			(start -0.120396 0.3048)
			(end -0.120396 0.2794)
			(stroke
				(width 0.1)
				(type default)
			)
			(layer "B.Fab")
		)
		(fp_line
			(start -0.67945 0.3048)
			(end -0.120396 0.3048)
			(stroke
				(width 0.1)
				(type default)
			)
			(layer "B.Fab")
		)
		(pad "1" smd circle
			(at 0.40005 0 270)
			(size 0 0)
			(layers "B.Cu" "B.Mask" "B.Paste")
			(net "LED_PWRGD_PVDDIO_P1_R")
		)
		(pad "2" smd circle
			(at -0.40005 0 270)
			(size 0 0)
			(layers "B.Cu" "B.Mask" "B.Paste")
			(net "P3V3_AUX")
		)
	)
	(footprint ""
		(layer "B.Cu")
		(at 287.986978 -419.04285)
		(property "Reference" "C79"
			(at 0 0 0)
			(layer "B.SilkS")
			(hide yes)
			(effects
				(font
					(size 1.27 1.27)
				)
				(justify mirror)
			)
		)
		(property "Value" ""
			(at 0 0 0)
			(layer "B.Fab")
			(effects
				(font
					(size 1.27 1.27)
				)
				(justify mirror)
			)
		)
		(duplicate_pad_numbers_are_jumpers no)
		(fp_line
			(start -0.7874 -0.4064)
			(end -0.7874 0.4064)
			(stroke
				(width 0.1524)
				(type default)
			)
			(layer "B.SilkS")
		)
		(fp_line
			(start -0.7874 0.4064)
			(end 0.7874 0.4064)
			(stroke
				(width 0.1524)
				(type default)
			)
			(layer "B.SilkS")
		)
		(fp_line
			(start 0.7874 -0.4064)
			(end -0.7874 -0.4064)
			(stroke
				(width 0.1524)
				(type default)
			)
			(layer "B.SilkS")
		)
		(fp_line
			(start 0.7874 0.4064)
			(end 0.7874 -0.4064)
			(stroke
				(width 0.1524)
				(type default)
			)
			(layer "B.SilkS")
		)
		(fp_line
			(start -0.67945 -0.3048)
			(end -0.67945 0.3048)
			(stroke
				(width 0.1)
				(type default)
			)
			(layer "B.Fab")
		)
		(fp_line
			(start -0.67945 0.3048)
			(end -0.120396 0.3048)
			(stroke
				(width 0.1)
				(type default)
			)
			(layer "B.Fab")
		)
		(fp_line
			(start -0.12065 -0.3048)
			(end -0.67945 -0.3048)
			(stroke
				(width 0.1)
				(type default)
			)
			(layer "B.Fab")
		)
		(fp_line
			(start -0.12065 -0.2794)
			(end -0.12065 -0.3048)
			(stroke
				(width 0.1)
				(type default)
			)
			(layer "B.Fab")
		)
		(fp_line
			(start -0.120396 0.2794)
			(end 0.12065 0.2794)
			(stroke
				(width 0.1)
				(type default)
			)
			(layer "B.Fab")
		)
		(fp_line
			(start -0.120396 0.3048)
			(end -0.120396 0.2794)
			(stroke
				(width 0.1)
				(type default)
			)
			(layer "B.Fab")
		)
		(fp_line
			(start 0.12065 -0.305054)
			(end 0.12065 -0.2794)
			(stroke
				(width 0.1)
				(type default)
			)
			(layer "B.Fab")
		)
		(fp_line
			(start 0.12065 -0.2794)
			(end -0.12065 -0.2794)
			(stroke
				(width 0.1)
				(type default)
			)
			(layer "B.Fab")
		)
		(fp_line
			(start 0.12065 0.2794)
			(end 0.12065 0.3048)
			(stroke
				(width 0.1)
				(type default)
			)
			(layer "B.Fab")
		)
		(fp_line
			(start 0.12065 0.3048)
			(end 0.67945 0.3048)
			(stroke
				(width 0.1)
				(type default)
			)
			(layer "B.Fab")
		)
		(fp_line
			(start 0.67945 -0.305054)
			(end 0.12065 -0.305054)
			(stroke
				(width 0.1)
				(type default)
			)
			(layer "B.Fab")
		)
		(fp_line
			(start 0.67945 0.3048)
			(end 0.67945 -0.305054)
			(stroke
				(width 0.1)
				(type default)
			)
			(layer "B.Fab")
		)
		(pad "1" smd circle
			(at 0.40005 0 180)
			(size 0 0)
			(layers "B.Cu" "B.Mask" "B.Paste")
			(net "P3V3_9ZXL045_P0_VDD")
		)
		(pad "2" smd circle
			(at -0.40005 0 180)
			(size 0 0)
			(layers "B.Cu" "B.Mask" "B.Paste")
			(net "GND")
		)
	)
)
